# TIMECARD (Time Appliance Project (Time Card)) — schematic netlist excerpt (pin names and nets, part order shuffled) for the footprints in the layout excerpt that follows; sources: Cadence DE-HDL packaged netlist, KiCad conversion of R4006-B0001-02_R01.brd

C223  CAPACITOR  0.1UF 10V 10%  pkg SMC_0402R_H022  page 14 : \1\ = XP3R3V_FPGA ; \2\ = SG
R31  RESISTOR  0OHM -  pkg SMC_0402R_H016  page 32 : \1\ = XP5R0V_BT ; \2\ = UNNAMED_516_CAPACITOR_I27_1

(kicad_pcb
	(version 20260206)
	(generator "pcbnew")
	(generator_version "10.0")
	(general
		(thickness 1.6)
		(legacy_teardrops no)
	)
	(paper "A4")
	(title_block
		(title "timecard-production-celestica-r4006 — R4006-B0001-02_R01.brd")
		(comment 1 "Time Appliance Project (Time Card) / footprints 1029-1030 of 1113")
	)
	(layers
		(0 "F.Cu" signal "TOP")
		(4 "In1.Cu" signal "L02_GND1")
		(6 "In2.Cu" signal "L03_SIG1")
		(8 "In3.Cu" signal "L04_GND2")
		(10 "In4.Cu" signal "L05_VCC1")
		(12 "In5.Cu" signal "L06_VCC2")
		(14 "In6.Cu" signal "L07_GND3")
		(16 "In7.Cu" signal "L08_SIG2")
		(18 "In8.Cu" signal "L09_GND4")
		(2 "B.Cu" signal "BOTTOM")
		(9 "F.Adhes" user "F.Adhesive")
		(11 "B.Adhes" user "B.Adhesive")
		(13 "F.Paste" user "Package Geometry/Pastemask Top")
		(15 "B.Paste" user "Package Geometry/Pastemask Bottom")
		(5 "F.SilkS" user "Ref Des/Silkscreen Top")
		(7 "B.SilkS" user "Ref Des/Silkscreen Bottom")
		(1 "F.Mask" user "Board Geometry/Soldermask Top")
		(3 "B.Mask" user "Board Geometry/Soldermask Bottom")
		(17 "Dwgs.User" user "User.Drawings")
		(19 "Cmts.User" user "User.Comments")
		(21 "Eco1.User" user "User.Eco1")
		(23 "Eco2.User" user "User.Eco2")
		(25 "Edge.Cuts" user "Board Geometry/Outline")
		(27 "Margin" user)
		(31 "F.CrtYd" user "Package Geometry/Place Bound Top")
		(29 "B.CrtYd" user "Package Geometry/Place Bound Bottom")
		(35 "F.Fab" user "Ref Des/Assembly Top")
		(33 "B.Fab" user "Ref Des/Assembly Bottom")
	)
	(footprint ""
		(layer "B.Cu")
		(at 41.783 -98.679 180)
		(property "Reference" "R31"
			(at 0.762 1.23063 0)
			(unlocked yes)
			(layer "B.SilkS")
			(effects
				(font
					(size 0.7874 0.5842)
					(thickness 0.1524)
				)
				(justify mirror)
			)
		)
		(property "Value" "VAL*"
			(at -0.02032 2.13233 180)
			(unlocked yes)
			(layer "B.Fab")
			(hide yes)
			(effects
				(font
					(size 0.7874 0.5842)
					(thickness 0.1524)
				)
				(justify mirror)
			)
		)
		(property "Tolerance" "TOL*"
			(at -0.044704 3.05435 180)
			(unlocked yes)
			(layer "Cmts.User")
			(hide yes)
			(effects
				(font
					(size 0.7874 0.5842)
					(thickness 0.1524)
				)
				(justify mirror)
			)
		)
		(property "User Part Number" "PARTNUM*"
			(at -0.02032 4.024884 180)
			(unlocked yes)
			(layer "Cmts.User")
			(hide yes)
			(effects
				(font
					(size 0.7874 0.5842)
					(thickness 0.1524)
				)
				(justify mirror)
			)
		)
		(property "Device Type" "RESISTOR-G155-100R0-J0,0OHM,-"
			(at -0.008382 1.210564 180)
			(unlocked yes)
			(layer "B.Fab")
			(hide yes)
			(effects
				(font
					(size 0.7874 0.5842)
					(thickness 0.1524)
				)
				(justify mirror)
			)
		)
		(duplicate_pad_numbers_are_jumpers no)
		(fp_line
			(start 1.143 0.5588)
			(end -1.143 0.5588)
			(stroke
				(width 0.1)
				(type default)
			)
			(layer "B.SilkS")
		)
		(fp_line
			(start 1.143 -0.5588)
			(end 1.143 0.5588)
			(stroke
				(width 0.1)
				(type default)
			)
			(layer "B.SilkS")
		)
		(fp_line
			(start -1.143 0.5588)
			(end -1.143 -0.5588)
			(stroke
				(width 0.1)
				(type default)
			)
			(layer "B.SilkS")
		)
		(fp_line
			(start -1.143 -0.5588)
			(end 1.143 -0.5588)
			(stroke
				(width 0.1)
				(type default)
			)
			(layer "B.SilkS")
		)
		(fp_poly
			(pts
				(xy 1.143 0.5588) (xy -1.143 0.5588) (xy -1.143 -0.5588) (xy 1.143 -0.5588)
			)
			(stroke
				(width 0)
				(type default)
			)
			(fill no)
			(layer "B.CrtYd")
		)
		(fp_line
			(start 0.508 0.3048)
			(end -0.508 0.3048)
			(stroke
				(width 0.1)
				(type default)
			)
			(layer "B.Fab")
		)
		(fp_line
			(start 0.508 -0.3048)
			(end 0.508 0.3048)
			(stroke
				(width 0.1)
				(type default)
			)
			(layer "B.Fab")
		)
		(fp_line
			(start -0.508 0.3048)
			(end -0.508 -0.3048)
			(stroke
				(width 0.1)
				(type default)
			)
			(layer "B.Fab")
		)
		(fp_line
			(start -0.508 -0.3048)
			(end 0.508 -0.3048)
			(stroke
				(width 0.1)
				(type default)
			)
			(layer "B.Fab")
		)
		(pad "1" smd rect
			(at 0.5334 0)
			(size 0.7112 0.6096)
			(layers "B.Cu" "B.Mask" "B.Paste")
			(net "XP5R0V_BT")
		)
		(pad "2" smd rect
			(at -0.5334 0)
			(size 0.7112 0.6096)
			(layers "B.Cu" "B.Mask" "B.Paste")
			(net "UNNAMED_516_CAPACITOR_I27_1")
		)
		(zone
			(layer "B.Cu")
			(hatch none 0.5)
			(connect_pads
				(clearance 0)
			)
			(min_thickness 0.25)
			(keepout
				(tracks not_allowed)
				(vias allowed)
				(pads allowed)
				(copperpour not_allowed)
				(footprints allowed)
			)
			(placement
				(enabled no)
				(sheetname "")
			)
			(fill
				(thermal_gap 0.5)
				(thermal_bridge_width 0.5)
				(island_removal_mode 0)
			)
			(polygon
				(pts
					(xy 41.7068 -98.9838) (xy 41.7068 -98.3742) (xy 41.8592 -98.3742) (xy 41.8592 -98.9838)
				)
			)
		)
		(zone
			(layer "B.Cu")
			(hatch none 0.5)
			(connect_pads
				(clearance 0)
			)
			(min_thickness 0.25)
			(keepout
				(tracks allowed)
				(vias not_allowed)
				(pads allowed)
				(copperpour not_allowed)
				(footprints allowed)
			)
			(placement
				(enabled no)
				(sheetname "")
			)
			(fill
				(thermal_gap 0.5)
				(thermal_bridge_width 0.5)
				(island_removal_mode 0)
			)
			(polygon
				(pts
					(xy 41.7068 -98.9838) (xy 41.7068 -98.3742) (xy 41.8592 -98.3742) (xy 41.8592 -98.9838)
				)
			)
		)
	)
	(footprint ""
		(layer "B.Cu")
		(at 111.847122 -55.323232 -90)
		(property "Reference" "C223"
			(at -2.207768 -0.008128 270)
			(unlocked yes)
			(layer "B.SilkS")
			(effects
				(font
					(size 0.635 0.4064)
					(thickness 0.1524)
				)
				(justify mirror)
			)
		)
		(property "Value" "VAL*"
			(at 0 3.718306 270)
			(unlocked yes)
			(layer "B.Fab")
			(hide yes)
			(effects
				(font
					(size 0.7874 0.5842)
					(thickness 0.127)
				)
				(justify mirror)
			)
		)
		(property "Tolerance" "TOL*"
			(at 0 4.861306 270)
			(unlocked yes)
			(layer "Cmts.User")
			(hide yes)
			(effects
				(font
					(size 0.7874 0.5842)
					(thickness 0.127)
				)
				(justify mirror)
			)
		)
		(property "User Part Number" "PARTNUM*"
			(at 0 2.575306 270)
			(unlocked yes)
			(layer "Cmts.User")
			(hide yes)
			(effects
				(font
					(size 0.7874 0.5842)
					(thickness 0.127)
				)
				(justify mirror)
			)
		)
		(property "Device Type" "CAPACITOR-G105-0B104-CK,0.1UF,A"
			(at 0 1.432306 270)
			(unlocked yes)
			(layer "B.Fab")
			(hide yes)
			(effects
				(font
					(size 0.7874 0.5842)
					(thickness 0.127)
				)
				(justify mirror)
			)
		)
		(duplicate_pad_numbers_are_jumpers no)
		(fp_line
			(start -0.970026 0.4699)
			(end 0.970026 0.4699)
			(stroke
				(width 0.1)
				(type default)
			)
			(layer "B.SilkS")
		)
		(fp_line
			(start 0.970026 0.4699)
			(end 0.970026 -0.4699)
			(stroke
				(width 0.1)
				(type default)
			)
			(layer "B.SilkS")
		)
		(fp_line
			(start -0.970026 -0.4699)
			(end -0.970026 0.4699)
			(stroke
				(width 0.1)
				(type default)
			)
			(layer "B.SilkS")
		)
		(fp_line
			(start 0.970026 -0.4699)
			(end -0.970026 -0.4699)
			(stroke
				(width 0.1)
				(type default)
			)
			(layer "B.SilkS")
		)
		(fp_poly
			(pts
				(xy 0.970026 0.4699) (xy -0.970026 0.4699) (xy -0.970026 -0.4699) (xy 0.970026 -0.4699)
			)
			(stroke
				(width 0)
				(type default)
			)
			(fill no)
			(layer "B.CrtYd")
		)
		(fp_line
			(start -0.508 0.3048)
			(end 0.508 0.3048)
			(stroke
				(width 0.1)
				(type default)
			)
			(layer "B.Fab")
		)
		(fp_line
			(start 0.508 0.3048)
			(end 0.508 -0.3048)
			(stroke
				(width 0.1)
				(type default)
			)
			(layer "B.Fab")
		)
		(fp_line
			(start -0.508 -0.3048)
			(end -0.508 0.3048)
			(stroke
				(width 0.1)
				(type default)
			)
			(layer "B.Fab")
		)
		(fp_line
			(start 0.508 -0.3048)
			(end -0.508 -0.3048)
			(stroke
				(width 0.1)
				(type default)
			)
			(layer "B.Fab")
		)
		(pad "1" smd circle
			(at 0.500126 0 90)
			(size 0.635 0.635)
			(layers "B.Cu" "B.Mask" "B.Paste")
			(net "XP3R3V_FPGA")
		)
		(pad "2" smd circle
			(at -0.500126 0 90)
			(size 0.635 0.635)
			(layers "B.Cu" "B.Mask" "B.Paste")
			(net "SG")
		)
	)
)
